(kicad_pcb
	(version 20241229)
	(generator "pcbnew")
	(generator_version "9.0")
	(general
		(thickness 1.61)
		(legacy_teardrops no)
	)
	(paper "A3")
	(title_block
		(title "SO-DIMM DDR5 Tester")
		(date "2025-11-26")
		(rev "1.3.0")
		(comment 9 "footprints 1-7 of 627")
	)
	(layers
		(0 "F.Cu" signal)
		(4 "In1.Cu" power)
		(6 "In2.Cu" mixed)
		(8 "In3.Cu" power)
		(10 "In4.Cu" mixed)
		(12 "In5.Cu" power)
		(14 "In6.Cu" mixed)
		(16 "In7.Cu" power)
		(18 "In8.Cu" power)
		(20 "In9.Cu" mixed)
		(22 "In10.Cu" power)
		(2 "B.Cu" signal)
		(9 "F.Adhes" user "F.Adhesive")
		(11 "B.Adhes" user "B.Adhesive")
		(13 "F.Paste" user)
		(15 "B.Paste" user)
		(5 "F.SilkS" user "F.Silkscreen")
		(7 "B.SilkS" user "B.Silkscreen")
		(1 "F.Mask" user)
		(3 "B.Mask" user)
		(17 "Dwgs.User" user "User.Drawings")
		(19 "Cmts.User" user "User.Comments")
		(21 "Eco1.User" user "User.Eco1")
		(23 "Eco2.User" user "User.Eco2")
		(25 "Edge.Cuts" user)
		(27 "Margin" user)
		(31 "F.CrtYd" user "F.Courtyard")
		(29 "B.CrtYd" user "B.Courtyard")
		(35 "F.Fab" user)
		(33 "B.Fab" user)
	)
	(footprint "antmicro-footprints:C_0402_1005Metric"
		(layer "F.Cu")
		(at 90.690501 171.536 90)
		(descr "Capacitor SMD 0402")
		(tags "capacitor SMD 0402")
		(property "Reference" "C116"
			(at 0 -0.699 90)
			(layer "F.SilkS")
			(hide yes)
			(effects
				(font
					(size 0.7 0.7)
					(thickness 0.15)
				)
				(justify left bottom)
			)
		)
		(property "Value" "C_4u7_0402"
			(at -1.022927 2.155213 90)
			(layer "F.Fab")
			(effects
				(font
					(size 0.7 0.7)
					(thickness 0.15)
				)
				(justify left bottom)
			)
		)
		(property "Datasheet" "https://www.murata.com/products/productdetail?partno=GRM155R61A475MEAA%23"
			(at 0 0 90)
			(layer "F.Fab")
			(hide yes)
			(effects
				(font
					(size 1.27 1.27)
					(thickness 0.15)
				)
			)
		)
		(property "Author" "Antmicro"
			(at 262.226501 80.845499 0)
			(layer "F.Fab")
			(hide yes)
			(effects
				(font
					(size 1 1)
					(thickness 0.15)
				)
			)
		)
		(property "Dielectric" ""
			(at 262.226501 80.845499 0)
			(layer "F.Fab")
			(hide yes)
			(effects
				(font
					(size 1 1)
					(thickness 0.15)
				)
			)
		)
		(property "License" "Apache-2.0"
			(at 262.226501 80.845499 0)
			(layer "F.Fab")
			(hide yes)
			(effects
				(font
					(size 1 1)
					(thickness 0.15)
				)
			)
		)
		(property "MPN" "GRM155R61A475MEAAD"
			(at 262.226501 80.845499 0)
			(layer "F.Fab")
			(hide yes)
			(effects
				(font
					(size 1 1)
					(thickness 0.15)
				)
			)
		)
		(property "Manufacturer" "Murata"
			(at 262.226501 80.845499 0)
			(layer "F.Fab")
			(hide yes)
			(effects
				(font
					(size 1 1)
					(thickness 0.15)
				)
			)
		)
		(property "Val" "4u7"
			(at 262.226501 80.845499 0)
			(layer "F.Fab")
			(hide yes)
			(effects
				(font
					(size 1 1)
					(thickness 0.15)
				)
			)
		)
		(property "Voltage" ""
			(at 262.226501 80.845499 0)
			(layer "F.Fab")
			(hide yes)
			(effects
				(font
					(size 1 1)
					(thickness 0.15)
				)
			)
		)
		(sheetname "/Debug FTDI/")
		(sheetfile "debug-ftdi.kicad_sch")
		(attr smd)
		(fp_rect
			(start -0.9659 -0.481258)
			(end 0.9649 0.458742)
			(stroke
				(width 0.05)
				(type solid)
			)
			(fill no)
			(layer "F.CrtYd")
		)
		(fp_line
			(start 0.499 -0.25)
			(end 0.499 0.248)
			(stroke
				(width 0.15)
				(type solid)
			)
			(layer "F.Fab")
		)
		(fp_line
			(start -0.499 -0.25)
			(end 0.499 -0.25)
			(stroke
				(width 0.15)
				(type solid)
			)
			(layer "F.Fab")
		)
		(fp_line
			(start 0.499 0.248)
			(end -0.499 0.248)
			(stroke
				(width 0.15)
				(type solid)
			)
			(layer "F.Fab")
		)
		(fp_line
			(start -0.499 0.248)
			(end -0.499 -0.25)
			(stroke
				(width 0.15)
				(type solid)
			)
			(layer "F.Fab")
		)
		(pad "1" smd roundrect
			(at -0.484 0 90)
			(size 0.59 0.64)
			(layers "F.Cu" "F.Mask" "F.Paste")
			(roundrect_rratio 0.25)
			(net 5 "/Debug FTDI/FTDI_VPHY")
			(pintype "passive")
		)
		(pad "2" smd roundrect
			(at 0.484 0 90)
			(size 0.59 0.64)
			(layers "F.Cu" "F.Mask" "F.Paste")
			(roundrect_rratio 0.25)
			(net 1 "GND")
			(pintype "passive")
		)
	)
	(footprint "antmicro-footprints:C_0402_1005Metric"
		(layer "F.Cu")
		(at 95.272344 167.552328 90)
		(descr "Capacitor SMD 0402")
		(tags "capacitor SMD 0402")
		(property "Reference" "C123"
			(at 0 -0.699 90)
			(layer "F.SilkS")
			(hide yes)
			(effects
				(font
					(size 0.7 0.7)
					(thickness 0.15)
				)
				(justify left bottom)
			)
		)
		(property "Value" "C_100n_0402"
			(at -1.022927 2.155213 90)
			(layer "F.Fab")
			(effects
				(font
					(size 0.7 0.7)
					(thickness 0.15)
				)
				(justify left bottom)
			)
		)
		(property "Datasheet" "https://www.murata.com/products/productdetail?partno=GRM155R61H104KE14%23"
			(at 0 0 90)
			(layer "F.Fab")
			(hide yes)
			(effects
				(font
					(size 1.27 1.27)
					(thickness 0.15)
				)
			)
		)
		(property "Author" "Antmicro"
			(at 262.824672 72.279984 0)
			(layer "F.Fab")
			(hide yes)
			(effects
				(font
					(size 1 1)
					(thickness 0.15)
				)
			)
		)
		(property "Dielectric" "X5R"
			(at 262.824672 72.279984 0)
			(layer "F.Fab")
			(hide yes)
			(effects
				(font
					(size 1 1)
					(thickness 0.15)
				)
			)
		)
		(property "License" "Apache-2.0"
			(at 262.824672 72.279984 0)
			(layer "F.Fab")
			(hide yes)
			(effects
				(font
					(size 1 1)
					(thickness 0.15)
				)
			)
		)
		(property "MPN" "GRM155R61H104KE14D"
			(at 262.824672 72.279984 0)
			(layer "F.Fab")
			(hide yes)
			(effects
				(font
					(size 1 1)
					(thickness 0.15)
				)
			)
		)
		(property "Manufacturer" "Murata"
			(at 262.824672 72.279984 0)
			(layer "F.Fab")
			(hide yes)
			(effects
				(font
					(size 1 1)
					(thickness 0.15)
				)
			)
		)
		(property "Val" "100n"
			(at 262.824672 72.279984 0)
			(layer "F.Fab")
			(hide yes)
			(effects
				(font
					(size 1 1)
					(thickness 0.15)
				)
			)
		)
		(property "Voltage" "50V"
			(at 262.824672 72.279984 0)
			(layer "F.Fab")
			(hide yes)
			(effects
				(font
					(size 1 1)
					(thickness 0.15)
				)
			)
		)
		(sheetname "/Debug FTDI/")
		(sheetfile "debug-ftdi.kicad_sch")
		(attr smd)
		(fp_rect
			(start -0.9659 -0.481258)
			(end 0.9649 0.458742)
			(stroke
				(width 0.05)
				(type solid)
			)
			(fill no)
			(layer "F.CrtYd")
		)
		(fp_line
			(start 0.499 -0.25)
			(end 0.499 0.248)
			(stroke
				(width 0.15)
				(type solid)
			)
			(layer "F.Fab")
		)
		(fp_line
			(start -0.499 -0.25)
			(end 0.499 -0.25)
			(stroke
				(width 0.15)
				(type solid)
			)
			(layer "F.Fab")
		)
		(fp_line
			(start 0.499 0.248)
			(end -0.499 0.248)
			(stroke
				(width 0.15)
				(type solid)
			)
			(layer "F.Fab")
		)
		(fp_line
			(start -0.499 0.248)
			(end -0.499 -0.25)
			(stroke
				(width 0.15)
				(type solid)
			)
			(layer "F.Fab")
		)
		(pad "1" smd roundrect
			(at -0.484 0 90)
			(size 0.59 0.64)
			(layers "F.Cu" "F.Mask" "F.Paste")
			(roundrect_rratio 0.25)
			(net 8 "/Debug FTDI/FTDI_VCORE")
			(pintype "passive")
		)
		(pad "2" smd roundrect
			(at 0.484 0 90)
			(size 0.59 0.64)
			(layers "F.Cu" "F.Mask" "F.Paste")
			(roundrect_rratio 0.25)
			(net 1 "GND")
			(pintype "passive")
		)
	)
	(footprint "antmicro-footprints:Resonator_SMD_Abracon_ABM8G_3.2x2.5mm"
		(layer "F.Cu")
		(at 91.898501 166.925 90)
		(property "Reference" "Y1"
			(at -1.75 -1.75 270)
			(layer "F.SilkS")
			(effects
				(font
					(size 0.7 0.7)
					(thickness 0.15)
				)
				(justify left bottom)
			)
		)
		(property "Value" "Resonator_12MHz_ABM8G"
			(at -1.75 2.548 90)
			(layer "F.Fab")
			(effects
				(font
					(size 0.7 0.7)
					(thickness 0.15)
				)
				(justify left bottom)
			)
		)
		(property "Datasheet" "https://abracon.com/Resonators/ABM8G.pdf"
			(at 0 0 90)
			(layer "F.Fab")
			(hide yes)
			(effects
				(font
					(size 1.27 1.27)
					(thickness 0.15)
				)
			)
		)
		(property "Author" "Antmicro"
			(at 258.823501 75.026499 0)
			(layer "F.Fab")
			(hide yes)
			(effects
				(font
					(size 1 1)
					(thickness 0.15)
				)
			)
		)
		(property "License" "Apache-2.0"
			(at 258.823501 75.026499 0)
			(layer "F.Fab")
			(hide yes)
			(effects
				(font
					(size 1 1)
					(thickness 0.15)
				)
			)
		)
		(property "MPN" "ABM8G-12.000MHZ-18-D2Y-T"
			(at 258.823501 75.026499 0)
			(layer "F.Fab")
			(hide yes)
			(effects
				(font
					(size 1 1)
					(thickness 0.15)
				)
			)
		)
		(property "Manufacturer" "Abracon"
			(at 258.823501 75.026499 0)
			(layer "F.Fab")
			(hide yes)
			(effects
				(font
					(size 1 1)
					(thickness 0.15)
				)
			)
		)
		(property "Val" "12 MHz"
			(at 258.823501 75.026499 0)
			(layer "F.Fab")
			(hide yes)
			(effects
				(font
					(size 1 1)
					(thickness 0.15)
				)
			)
		)
		(sheetname "/Debug FTDI/")
		(sheetfile "debug-ftdi.kicad_sch")
		(attr smd)
		(fp_line
			(start -0.35 -1.25)
			(end 0.45 -1.25)
			(stroke
				(width 0.15)
				(type solid)
			)
			(layer "F.SilkS")
		)
		(fp_line
			(start 1.6 0.3)
			(end 1.6 -0.2)
			(stroke
				(width 0.15)
				(type solid)
			)
			(layer "F.SilkS")
		)
		(fp_line
			(start -1.6 0.3)
			(end -1.6 -0.2)
			(stroke
				(width 0.15)
				(type solid)
			)
			(layer "F.SilkS")
		)
		(fp_line
			(start -0.35 1.25)
			(end 0.45 1.25)
			(stroke
				(width 0.15)
				(type solid)
			)
			(layer "F.SilkS")
		)
		(fp_circle
			(center -1.75 1.5)
			(end -1.7 1.5)
			(stroke
				(width 0.15)
				(type solid)
			)
			(fill no)
			(layer "F.SilkS")
		)
		(fp_rect
			(start -1.907 -1.55)
			(end 2.006 1.649)
			(stroke
				(width 0.05)
				(type solid)
			)
			(fill no)
			(layer "F.CrtYd")
		)
		(pad "1" smd roundrect
			(at -1.101 0.949 90)
			(size 1.3 1.1)
			(layers "F.Cu" "F.Mask" "F.Paste")
			(roundrect_rratio 0)
			(chamfer_ratio 0.2)
			(chamfer bottom_left)
			(net 4 "/Debug FTDI/FTDI_XI")
			(pintype "passive")
		)
		(pad "2" smd rect
			(at 1.199 0.949 90)
			(size 1.3 1.1)
			(layers "F.Cu" "F.Mask" "F.Paste")
			(net 1 "GND")
			(pinfunction "SH")
			(pintype "passive")
		)
		(pad "3" smd rect
			(at 1.199 -0.85 90)
			(size 1.3 1.1)
			(layers "F.Cu" "F.Mask" "F.Paste")
			(net 7 "/Debug FTDI/FTDI_XO")
			(pintype "passive")
		)
		(pad "4" smd rect
			(at -1.101 -0.85 90)
			(size 1.3 1.1)
			(layers "F.Cu" "F.Mask" "F.Paste")
			(net 1 "GND")
			(pinfunction "SH")
			(pintype "passive")
		)
	)
	(footprint "antmicro-footprints:R_0402_1005Metric"
		(layer "F.Cu")
		(at 106.775 175.02)
		(descr "Resistor SMD 0402")
		(tags "resistor SMD 0402")
		(property "Reference" "R52"
			(at -1.122484 -0.772697 0)
			(layer "F.SilkS")
			(hide yes)
			(effects
				(font
					(size 0.7 0.7)
					(thickness 0.15)
				)
				(justify left bottom)
			)
		)
		(property "Value" "R_22R_0402"
			(at -1.011843 1.772047 0)
			(layer "F.Fab")
			(effects
				(font
					(size 0.7 0.7)
					(thickness 0.15)
				)
				(justify left bottom)
			)
		)
		(property "Datasheet" "https://www.bourns.com/docs/product-datasheets/cr.pdf"
			(at 0 0 0)
			(layer "F.Fab")
			(hide yes)
			(effects
				(font
					(size 1.27 1.27)
					(thickness 0.15)
				)
			)
		)
		(property "Author" "Antmicro"
			(at 0 0 0)
			(layer "F.Fab")
			(hide yes)
			(effects
				(font
					(size 1 1)
					(thickness 0.15)
				)
			)
		)
		(property "License" "Apache-2.0"
			(at 0 0 0)
			(layer "F.Fab")
			(hide yes)
			(effects
				(font
					(size 1 1)
					(thickness 0.15)
				)
			)
		)
		(property "MPN" "CR0402-FX-22R0GLF"
			(at 0 0 0)
			(layer "F.Fab")
			(hide yes)
			(effects
				(font
					(size 1 1)
					(thickness 0.15)
				)
			)
		)
		(property "Manufacturer" "Bourns"
			(at 0 0 0)
			(layer "F.Fab")
			(hide yes)
			(effects
				(font
					(size 1 1)
					(thickness 0.15)
				)
			)
		)
		(property "Tolerance" "1%"
			(at 0 0 0)
			(layer "F.Fab")
			(hide yes)
			(effects
				(font
					(size 1 1)
					(thickness 0.15)
				)
			)
		)
		(property "Val" "22R"
			(at 0 0 0)
			(layer "F.Fab")
			(hide yes)
			(effects
				(font
					(size 1 1)
					(thickness 0.15)
				)
			)
		)
		(sheetname "/Debug FTDI/")
		(sheetfile "debug-ftdi.kicad_sch")
		(attr smd)
		(fp_rect
			(start -0.93 -0.47)
			(end 0.93 0.47)
			(stroke
				(width 0.05)
				(type solid)
			)
			(fill no)
			(layer "F.CrtYd")
		)
		(fp_rect
			(start -0.5 -0.25)
			(end 0.5 0.25)
			(stroke
				(width 0.15)
				(type solid)
			)
			(fill no)
			(layer "F.Fab")
		)
		(pad "1" smd roundrect
			(at -0.485 0)
			(size 0.59 0.64)
			(layers "F.Cu" "F.Mask" "F.Paste")
			(roundrect_rratio 0.25)
			(net 746 "Net-(U32-B1)")
			(pintype "passive")
		)
		(pad "2" smd roundrect
			(at 0.485 0)
			(size 0.59 0.64)
			(layers "F.Cu" "F.Mask" "F.Paste")
			(roundrect_rratio 0.25)
			(net 641 "/Debug FTDI/UART0.TX")
			(pintype "passive")
		)
	)
	(footprint "antmicro-footprints:R_0402_1005Metric"
		(layer "F.Cu")
		(at 106.775 176.045)
		(descr "Resistor SMD 0402")
		(tags "resistor SMD 0402")
		(property "Reference" "R53"
			(at -1.122484 -0.772697 0)
			(layer "F.SilkS")
			(hide yes)
			(effects
				(font
					(size 0.7 0.7)
					(thickness 0.15)
				)
				(justify left bottom)
			)
		)
		(property "Value" "R_22R_0402"
			(at -1.011843 1.772047 0)
			(layer "F.Fab")
			(effects
				(font
					(size 0.7 0.7)
					(thickness 0.15)
				)
				(justify left bottom)
			)
		)
		(property "Datasheet" "https://www.bourns.com/docs/product-datasheets/cr.pdf"
			(at 0 0 0)
			(layer "F.Fab")
			(hide yes)
			(effects
				(font
					(size 1.27 1.27)
					(thickness 0.15)
				)
			)
		)
		(property "Author" "Antmicro"
			(at 0 0 0)
			(layer "F.Fab")
			(hide yes)
			(effects
				(font
					(size 1 1)
					(thickness 0.15)
				)
			)
		)
		(property "License" "Apache-2.0"
			(at 0 0 0)
			(layer "F.Fab")
			(hide yes)
			(effects
				(font
					(size 1 1)
					(thickness 0.15)
				)
			)
		)
		(property "MPN" "CR0402-FX-22R0GLF"
			(at 0 0 0)
			(layer "F.Fab")
			(hide yes)
			(effects
				(font
					(size 1 1)
					(thickness 0.15)
				)
			)
		)
		(property "Manufacturer" "Bourns"
			(at 0 0 0)
			(layer "F.Fab")
			(hide yes)
			(effects
				(font
					(size 1 1)
					(thickness 0.15)
				)
			)
		)
		(property "Tolerance" "1%"
			(at 0 0 0)
			(layer "F.Fab")
			(hide yes)
			(effects
				(font
					(size 1 1)
					(thickness 0.15)
				)
			)
		)
		(property "Val" "22R"
			(at 0 0 0)
			(layer "F.Fab")
			(hide yes)
			(effects
				(font
					(size 1 1)
					(thickness 0.15)
				)
			)
		)
		(sheetname "/Debug FTDI/")
		(sheetfile "debug-ftdi.kicad_sch")
		(attr smd)
		(fp_rect
			(start -0.93 -0.47)
			(end 0.93 0.47)
			(stroke
				(width 0.05)
				(type solid)
			)
			(fill no)
			(layer "F.CrtYd")
		)
		(fp_rect
			(start -0.5 -0.25)
			(end 0.5 0.25)
			(stroke
				(width 0.15)
				(type solid)
			)
			(fill no)
			(layer "F.Fab")
		)
		(pad "1" smd roundrect
			(at -0.485 0)
			(size 0.59 0.64)
			(layers "F.Cu" "F.Mask" "F.Paste")
			(roundrect_rratio 0.25)
			(net 747 "Net-(U32-B2)")
			(pintype "passive")
		)
		(pad "2" smd roundrect
			(at 0.485 0)
			(size 0.59 0.64)
			(layers "F.Cu" "F.Mask" "F.Paste")
			(roundrect_rratio 0.25)
			(net 639 "/Debug FTDI/UART0.RX")
			(pintype "passive")
		)
	)
	(footprint "antmicro-footprints:R_0402_1005Metric"
		(layer "F.Cu")
		(at 106.78 171.26)
		(descr "Resistor SMD 0402")
		(tags "resistor SMD 0402")
		(property "Reference" "R54"
			(at -1.122484 -0.772697 0)
			(layer "F.SilkS")
			(hide yes)
			(effects
				(font
					(size 0.7 0.7)
					(thickness 0.15)
				)
				(justify left bottom)
			)
		)
		(property "Value" "R_22R_0402"
			(at -1.011843 1.772047 0)
			(layer "F.Fab")
			(effects
				(font
					(size 0.7 0.7)
					(thickness 0.15)
				)
				(justify left bottom)
			)
		)
		(property "Datasheet" "https://www.bourns.com/docs/product-datasheets/cr.pdf"
			(at 0 0 0)
			(layer "F.Fab")
			(hide yes)
			(effects
				(font
					(size 1.27 1.27)
					(thickness 0.15)
				)
			)
		)
		(property "Author" "Antmicro"
			(at 0 0 0)
			(layer "F.Fab")
			(hide yes)
			(effects
				(font
					(size 1 1)
					(thickness 0.15)
				)
			)
		)
		(property "License" "Apache-2.0"
			(at 0 0 0)
			(layer "F.Fab")
			(hide yes)
			(effects
				(font
					(size 1 1)
					(thickness 0.15)
				)
			)
		)
		(property "MPN" "CR0402-FX-22R0GLF"
			(at 0 0 0)
			(layer "F.Fab")
			(hide yes)
			(effects
				(font
					(size 1 1)
					(thickness 0.15)
				)
			)
		)
		(property "Manufacturer" "Bourns"
			(at 0 0 0)
			(layer "F.Fab")
			(hide yes)
			(effects
				(font
					(size 1 1)
					(thickness 0.15)
				)
			)
		)
		(property "Tolerance" "1%"
			(at 0 0 0)
			(layer "F.Fab")
			(hide yes)
			(effects
				(font
					(size 1 1)
					(thickness 0.15)
				)
			)
		)
		(property "Val" "22R"
			(at 0 0 0)
			(layer "F.Fab")
			(hide yes)
			(effects
				(font
					(size 1 1)
					(thickness 0.15)
				)
			)
		)
		(sheetname "/Debug FTDI/")
		(sheetfile "debug-ftdi.kicad_sch")
		(attr smd)
		(fp_rect
			(start -0.93 -0.47)
			(end 0.93 0.47)
			(stroke
				(width 0.05)
				(type solid)
			)
			(fill no)
			(layer "F.CrtYd")
		)
		(fp_rect
			(start -0.5 -0.25)
			(end 0.5 0.25)
			(stroke
				(width 0.15)
				(type solid)
			)
			(fill no)
			(layer "F.Fab")
		)
		(pad "1" smd roundrect
			(at -0.485 0)
			(size 0.59 0.64)
			(layers "F.Cu" "F.Mask" "F.Paste")
			(roundrect_rratio 0.25)
			(net 748 "Net-(U33-B1)")
			(pintype "passive")
		)
		(pad "2" smd roundrect
			(at 0.485 0)
			(size 0.59 0.64)
			(layers "F.Cu" "F.Mask" "F.Paste")
			(roundrect_rratio 0.25)
			(net 645 "/Debug FTDI/UART1.TX")
			(pintype "passive")
		)
	)
	(footprint "antmicro-footprints:R_0402_1005Metric"
		(layer "F.Cu")
		(at 106.78 172.26)
		(descr "Resistor SMD 0402")
		(tags "resistor SMD 0402")
		(property "Reference" "R55"
			(at -1.122484 -0.772697 0)
			(layer "F.SilkS")
			(hide yes)
			(effects
				(font
					(size 0.7 0.7)
					(thickness 0.15)
				)
				(justify left bottom)
			)
		)
		(property "Value" "R_22R_0402"
			(at -1.011843 1.772047 0)
			(layer "F.Fab")
			(effects
				(font
					(size 0.7 0.7)
					(thickness 0.15)
				)
				(justify left bottom)
			)
		)
		(property "Datasheet" "https://www.bourns.com/docs/product-datasheets/cr.pdf"
			(at 0 0 0)
			(layer "F.Fab")
			(hide yes)
			(effects
				(font
					(size 1.27 1.27)
					(thickness 0.15)
				)
			)
		)
		(property "Author" "Antmicro"
			(at 0 0 0)
			(layer "F.Fab")
			(hide yes)
			(effects
				(font
					(size 1 1)
					(thickness 0.15)
				)
			)
		)
		(property "License" "Apache-2.0"
			(at 0 0 0)
			(layer "F.Fab")
			(hide yes)
			(effects
				(font
					(size 1 1)
					(thickness 0.15)
				)
			)
		)
		(property "MPN" "CR0402-FX-22R0GLF"
			(at 0 0 0)
			(layer "F.Fab")
			(hide yes)
			(effects
				(font
					(size 1 1)
					(thickness 0.15)
				)
			)
		)
		(property "Manufacturer" "Bourns"
			(at 0 0 0)
			(layer "F.Fab")
			(hide yes)
			(effects
				(font
					(size 1 1)
					(thickness 0.15)
				)
			)
		)
		(property "Tolerance" "1%"
			(at 0 0 0)
			(layer "F.Fab")
			(hide yes)
			(effects
				(font
					(size 1 1)
					(thickness 0.15)
				)
			)
		)
		(property "Val" "22R"
			(at 0 0 0)
			(layer "F.Fab")
			(hide yes)
			(effects
				(font
					(size 1 1)
					(thickness 0.15)
				)
			)
		)
		(sheetname "/Debug FTDI/")
		(sheetfile "debug-ftdi.kicad_sch")
		(attr smd)
		(fp_rect
			(start -0.93 -0.47)
			(end 0.93 0.47)
			(stroke
				(width 0.05)
				(type solid)
			)
			(fill no)
			(layer "F.CrtYd")
		)
		(fp_rect
			(start -0.5 -0.25)
			(end 0.5 0.25)
			(stroke
				(width 0.15)
				(type solid)
			)
			(fill no)
			(layer "F.Fab")
		)
		(pad "1" smd roundrect
			(at -0.485 0)
			(size 0.59 0.64)
			(layers "F.Cu" "F.Mask" "F.Paste")
			(roundrect_rratio 0.25)
			(net 749 "Net-(U33-B2)")
			(pintype "passive")
		)
		(pad "2" smd roundrect
			(at 0.485 0)
			(size 0.59 0.64)
			(layers "F.Cu" "F.Mask" "F.Paste")
			(roundrect_rratio 0.25)
			(net 643 "/Debug FTDI/UART1.RX")
			(pintype "passive")
		)
	)
)
